(kicad_pcb
	(version 20260206)
	(generator "pcbnew")
	(generator_version "10.0")
	(general
		(thickness 1.6)
		(legacy_teardrops no)
	)
	(paper "A4")
	(title_block
		(title "v1-chassis-manager — T6M_CM_d_v01_1031_1645.brd")
		(comment 1 "Open CloudServer (Microsoft) / footprints 797-797 of 2512")
	)
	(layers
		(0 "F.Cu" signal "TOP")
		(4 "In1.Cu" signal "GND1")
		(6 "In2.Cu" signal "IN1")
		(8 "In3.Cu" signal "VCC1")
		(10 "In4.Cu" signal "VCC2")
		(12 "In5.Cu" signal "GND2")
		(14 "In6.Cu" signal "IN2")
		(16 "In7.Cu" signal "IN3")
		(18 "In8.Cu" signal "GND3")
		(2 "B.Cu" signal "BOTTOM")
		(9 "F.Adhes" user "F.Adhesive")
		(11 "B.Adhes" user "B.Adhesive")
		(13 "F.Paste" user "Package Geometry/Pastemask Top")
		(15 "B.Paste" user "Package Geometry/Pastemask Bottom")
		(5 "F.SilkS" user "Ref Des/Silkscreen Top")
		(7 "B.SilkS" user "Ref Des/Silkscreen Bottom")
		(1 "F.Mask" user "Board Geometry/Soldermask Top")
		(3 "B.Mask" user "Board Geometry/Soldermask Bottom")
		(17 "Dwgs.User" user "User.Drawings")
		(19 "Cmts.User" user "User.Comments")
		(21 "Eco1.User" user "User.Eco1")
		(23 "Eco2.User" user "User.Eco2")
		(25 "Edge.Cuts" user "Board Geometry/Outline")
		(27 "Margin" user)
		(31 "F.CrtYd" user "Package Geometry/Place Bound Top")
		(29 "B.CrtYd" user "Package Geometry/Place Bound Bottom")
		(35 "F.Fab" user "Ref Des/Assembly Top")
		(33 "B.Fab" user "Ref Des/Assembly Bottom")
	)
	(footprint ""
		(layer "F.Cu")
		(at 161.019998 -153.09723 -90)
		(property "Reference" "U37"
			(at 2.170176 -6.839204 90)
			(unlocked yes)
			(layer "F.SilkS")
			(effects
				(font
					(size 0.7874 0.5842)
					(thickness 0.1524)
				)
				(justify left)
			)
		)
		(property "Value" ""
			(at 0 0 270)
			(layer "F.Fab")
			(effects
				(font
					(size 1.27 1.27)
				)
			)
		)
		(duplicate_pad_numbers_are_jumpers no)
		(fp_line
			(start 0.249936 5.207)
			(end 0.249936 5.715)
			(stroke
				(width 0.1524)
				(type default)
			)
			(layer "F.SilkS")
		)
		(fp_line
			(start 2.750058 5.207)
			(end 2.750058 6.223)
			(stroke
				(width 0.1524)
				(type default)
			)
			(layer "F.SilkS")
		)
		(fp_line
			(start -4.474718 4.500118)
			(end -4.500118 4.474718)
			(stroke
				(width 0.1524)
				(type default)
			)
			(layer "F.SilkS")
		)
		(fp_line
			(start -4.0132 4.500118)
			(end -4.474718 4.500118)
			(stroke
				(width 0.1524)
				(type default)
			)
			(layer "F.SilkS")
		)
		(fp_line
			(start 4.500118 4.500118)
			(end 4.0132 4.500118)
			(stroke
				(width 0.1524)
				(type default)
			)
			(layer "F.SilkS")
		)
		(fp_line
			(start -4.500118 4.474718)
			(end -4.500118 4.0132)
			(stroke
				(width 0.1524)
				(type default)
			)
			(layer "F.SilkS")
		)
		(fp_line
			(start 4.500118 4.0386)
			(end 4.500118 4.500118)
			(stroke
				(width 0.1524)
				(type default)
			)
			(layer "F.SilkS")
		)
		(fp_line
			(start -5.207 3.24993)
			(end -5.715 3.24993)
			(stroke
				(width 0.1524)
				(type default)
			)
			(layer "F.SilkS")
		)
		(fp_line
			(start 5.207 2.750058)
			(end 5.715 2.750058)
			(stroke
				(width 0.1524)
				(type default)
			)
			(layer "F.SilkS")
		)
		(fp_line
			(start -5.207 0.750062)
			(end -6.223 0.750062)
			(stroke
				(width 0.1524)
				(type default)
			)
			(layer "F.SilkS")
		)
		(fp_line
			(start 5.207 0.249936)
			(end 6.223 0.249936)
			(stroke
				(width 0.1524)
				(type default)
			)
			(layer "F.SilkS")
		)
		(fp_line
			(start -5.207 -1.75006)
			(end -5.715 -1.75006)
			(stroke
				(width 0.1524)
				(type default)
			)
			(layer "F.SilkS")
		)
		(fp_line
			(start 5.207 -1.75006)
			(end 5.715 -1.75006)
			(stroke
				(width 0.1524)
				(type default)
			)
			(layer "F.SilkS")
		)
		(fp_line
			(start -4.487418 -4.004818)
			(end -4.004818 -4.487418)
			(stroke
				(width 0.1524)
				(type default)
			)
			(layer "F.SilkS")
		)
		(fp_line
			(start 4.0386 -4.500118)
			(end 4.500118 -4.500118)
			(stroke
				(width 0.1524)
				(type default)
			)
			(layer "F.SilkS")
		)
		(fp_line
			(start 4.500118 -4.500118)
			(end 4.500118 -4.0132)
			(stroke
				(width 0.1524)
				(type default)
			)
			(layer "F.SilkS")
		)
		(fp_line
			(start 0.750062 -5.207)
			(end 0.750062 -5.715)
			(stroke
				(width 0.1524)
				(type default)
			)
			(layer "F.SilkS")
		)
		(fp_line
			(start -1.75006 -5.2832)
			(end -1.75006 -6.2992)
			(stroke
				(width 0.1524)
				(type default)
			)
			(layer "F.SilkS")
		)
		(fp_line
			(start 3.24993 -5.2832)
			(end 3.24993 -6.2992)
			(stroke
				(width 0.1524)
				(type default)
			)
			(layer "F.SilkS")
		)
		(fp_poly
			(pts
				(xy -4.766564 -4.09067) (xy -5.448046 -5.564378) (xy -6.256274 -4.75615)
			)
			(stroke
				(width 0)
				(type default)
			)
			(fill yes)
			(layer "F.SilkS")
		)
		(fp_poly
			(pts
				(xy -4.500118 4.500118) (xy -3.8862 4.500118) (xy -3.8862 5.0292) (xy -3.8608 5.0292) (xy 3.8608 5.0292)
				(xy 3.8862 5.0292) (xy 3.8862 4.500118) (xy 4.500118 4.500118) (xy 4.500118 3.8862) (xy 5.0292 3.8862)
				(xy 5.0292 3.8608) (xy 5.0292 -3.8608) (xy 5.0292 -3.8862) (xy 4.500118 -3.8862) (xy 4.500118 -4.500118)
				(xy 3.8862 -4.500118) (xy 3.8862 -5.0292) (xy 3.8608 -5.0292) (xy -3.8608 -5.0292) (xy -3.8862 -5.0292)
				(xy -3.8862 -4.500118) (xy -4.500118 -4.500118) (xy -4.500118 -3.8862) (xy -5.0292 -3.8862) (xy -5.0292 -3.8608)
				(xy -5.0292 3.8608) (xy -5.0292 3.8862) (xy -4.500118 3.8862)
			)
			(stroke
				(width 0)
				(type default)
			)
			(fill no)
			(layer "F.CrtYd")
		)
		(fp_line
			(start -4.500118 4.500118)
			(end -4.500118 -4.500118)
			(stroke
				(width 0.1)
				(type default)
			)
			(layer "F.Fab")
		)
		(fp_line
			(start 4.500118 4.500118)
			(end -4.500118 4.500118)
			(stroke
				(width 0.1)
				(type default)
			)
			(layer "F.Fab")
		)
		(fp_line
			(start -4.500118 -4.500118)
			(end 4.500118 -4.500118)
			(stroke
				(width 0.1)
				(type default)
			)
			(layer "F.Fab")
		)
		(fp_line
			(start 4.500118 -4.500118)
			(end 4.500118 4.500118)
			(stroke
				(width 0.1)
				(type default)
			)
			(layer "F.Fab")
		)
		(fp_text user "17"
			(at -4.675124 5.771642 0)
			(unlocked yes)
			(layer "F.SilkS")
			(effects
				(font
					(size 0.635 0.4064)
					(thickness 0.1524)
				)
				(justify left)
			)
		)
		(fp_text user "32"
			(at 5.316982 5.525516 0)
			(unlocked yes)
			(layer "F.SilkS")
			(effects
				(font
					(size 0.635 0.4064)
					(thickness 0.1524)
				)
				(justify left)
			)
		)
		(fp_text user "16"
			(at -6.279388 4.348734 0)
			(unlocked yes)
			(layer "F.SilkS")
			(effects
				(font
					(size 0.635 0.4064)
					(thickness 0.1524)
				)
				(justify left)
			)
		)
		(fp_text user "33"
			(at 5.662422 3.985768 0)
			(unlocked yes)
			(layer "F.SilkS")
			(effects
				(font
					(size 0.635 0.4064)
					(thickness 0.1524)
				)
				(justify left)
			)
		)
		(fp_text user "48"
			(at 5.367782 -4.100576 0)
			(unlocked yes)
			(layer "F.SilkS")
			(effects
				(font
					(size 0.635 0.4064)
					(thickness 0.1524)
				)
				(justify left)
			)
		)
		(fp_text user "49"
			(at 4.03733 -5.404612 0)
			(unlocked yes)
			(layer "F.SilkS")
			(effects
				(font
					(size 0.635 0.4064)
					(thickness 0.1524)
				)
				(justify left)
			)
		)
		(pad "1" smd rect
			(at -4.549902 -3.750056 180)
			(size 0.254 0.9144)
			(layers "F.Cu" "F.Mask" "F.Paste")
			(net "P3V3_NODE1")
		)
		(pad "2" smd rect
			(at -4.549902 -3.24993 180)
			(size 0.254 0.9144)
			(layers "F.Cu" "F.Mask" "F.Paste")
			(net "LAN2_NC_SI_CLK_IN")
		)
		(pad "3" smd rect
			(at -4.549902 -2.750058 180)
			(size 0.254 0.9144)
			(layers "F.Cu" "F.Mask" "F.Paste")
			(net "LAN2_NC_SI_CRS_DV")
		)
		(pad "4" smd rect
			(at -4.549902 -2.249932 180)
			(size 0.254 0.9144)
			(layers "F.Cu" "F.Mask" "F.Paste")
			(net "P1V05_LAN2")
		)
		(pad "5" smd rect
			(at -4.549902 -1.75006 180)
			(size 0.254 0.9144)
			(layers "F.Cu" "F.Mask" "F.Paste")
			(net "LAN2_NC_SI_RXD1")
		)
		(pad "6" smd rect
			(at -4.549902 -1.249934 180)
			(size 0.254 0.9144)
			(layers "F.Cu" "F.Mask" "F.Paste")
			(net "LAN2_NC_SI_RXD0")
		)
		(pad "7" smd rect
			(at -4.549902 -0.750062 180)
			(size 0.254 0.9144)
			(layers "F.Cu" "F.Mask" "F.Paste")
			(net "LAN2_NC_SI_TX_EN")
		)
		(pad "8" smd rect
			(at -4.549902 -0.249936 180)
			(size 0.254 0.9144)
			(layers "F.Cu" "F.Mask" "F.Paste")
			(net "LAN2_NC_SI_TDX1")
		)
		(pad "9" smd rect
			(at -4.549902 0.249936 180)
			(size 0.254 0.9144)
			(layers "F.Cu" "F.Mask" "F.Paste")
			(net "LAN2_NC_SI_TDX0")
		)
		(pad "10" smd rect
			(at -4.549902 0.750062 180)
			(size 0.254 0.9144)
			(layers "F.Cu" "F.Mask" "F.Paste")
			(net "P3V3_NODE1")
		)
		(pad "11" smd rect
			(at -4.549902 1.249934 180)
			(size 0.254 0.9144)
			(layers "F.Cu" "F.Mask" "F.Paste")
			(net "P1V05_LAN2")
		)
		(pad "12" smd rect
			(at -4.549902 1.75006 180)
			(size 0.254 0.9144)
			(layers "F.Cu" "F.Mask" "F.Paste")
			(net "SPI_LAN2_NVM_SI")
		)
		(pad "13" smd rect
			(at -4.549902 2.249932 180)
			(size 0.254 0.9144)
			(layers "F.Cu" "F.Mask" "F.Paste")
			(net "SPI_LAN2_NVM_SK")
		)
		(pad "14" smd rect
			(at -4.549902 2.750058 180)
			(size 0.254 0.9144)
			(layers "F.Cu" "F.Mask" "F.Paste")
			(net "SPI_LAN2_NVM_SO")
		)
		(pad "15" smd rect
			(at -4.549902 3.24993 180)
			(size 0.254 0.9144)
			(layers "F.Cu" "F.Mask" "F.Paste")
			(net "SPI_LAN2_NVM_CS_N")
		)
		(pad "16" smd rect
			(at -4.549902 3.750056 180)
			(size 0.254 0.9144)
			(layers "F.Cu" "F.Mask" "F.Paste")
			(net "IRQ_LVC3_CPU_NODE1_WAKE_L")
		)
		(pad "17" smd rect
			(at -3.750056 4.549902 270)
			(size 0.254 0.9144)
			(layers "F.Cu" "F.Mask" "F.Paste")
			(net "PLT_RST_LAN2_N")
		)
		(pad "18" smd rect
			(at -3.24993 4.549902 270)
			(size 0.254 0.9144)
			(layers "F.Cu" "F.Mask" "F.Paste")
			(net "P1V05_LAN2")
		)
		(pad "19" smd rect
			(at -2.750058 4.549902 270)
			(size 0.254 0.9144)
			(layers "F.Cu" "F.Mask" "F.Paste")
			(net "P1V9_LAN2")
		)
		(pad "20" smd rect
			(at -2.249932 4.549902 270)
			(size 0.254 0.9144)
			(layers "F.Cu" "F.Mask" "F.Paste")
			(net "PCIE_LAN2_RX_C_DN")
		)
		(pad "21" smd rect
			(at -1.75006 4.549902 270)
			(size 0.254 0.9144)
			(layers "F.Cu" "F.Mask" "F.Paste")
			(net "PCIE_LAN2_RX_C_DP")
		)
		(pad "22" smd rect
			(at -1.249934 4.549902 270)
			(size 0.254 0.9144)
			(layers "F.Cu" "F.Mask" "F.Paste")
			(net "P1V9_LAN2")
		)
		(pad "23" smd rect
			(at -0.750062 4.549902 270)
			(size 0.254 0.9144)
			(layers "F.Cu" "F.Mask" "F.Paste")
			(net "P2E_CPU_NIC2_NODE1_TX_DN")
		)
		(pad "24" smd rect
			(at -0.249936 4.549902 270)
			(size 0.254 0.9144)
			(layers "F.Cu" "F.Mask" "F.Paste")
			(net "P2E_CPU_NIC2_NODE1_TX_DP")
		)
		(pad "25" smd rect
			(at 0.249936 4.549902 270)
			(size 0.254 0.9144)
			(layers "F.Cu" "F.Mask" "F.Paste")
			(net "CLK_100M_NIC2_NODE1_DN")
		)
		(pad "26" smd rect
			(at 0.750062 4.549902 270)
			(size 0.254 0.9144)
			(layers "F.Cu" "F.Mask" "F.Paste")
			(net "CLK_100M_NIC2_NODE1_DP")
		)
		(pad "27" smd rect
			(at 1.249934 4.549902 270)
			(size 0.254 0.9144)
			(layers "F.Cu" "F.Mask" "F.Paste")
			(net "P1V05_LAN2")
		)
		(pad "28" smd rect
			(at 1.75006 4.549902 270)
			(size 0.254 0.9144)
			(layers "F.Cu" "F.Mask" "F.Paste")
			(net "LAN2_DISABLE_N")
		)
		(pad "29" smd rect
			(at 2.249932 4.549902 270)
			(size 0.254 0.9144)
			(layers "F.Cu" "F.Mask" "F.Paste")
			(net "LAN2_TEST_EN")
		)
		(pad "30" smd rect
			(at 2.750058 4.549902 270)
			(size 0.254 0.9144)
			(layers "F.Cu" "F.Mask" "F.Paste")
			(net "LAN2_LED_ACT_N")
		)
		(pad "31" smd rect
			(at 3.24993 4.549902 270)
			(size 0.254 0.9144)
			(layers "F.Cu" "F.Mask" "F.Paste")
			(net "LAN2_LED_LINK_100_N")
		)
		(pad "32" smd rect
			(at 3.750056 4.549902 270)
			(size 0.254 0.9144)
			(layers "F.Cu" "F.Mask" "F.Paste")
			(net "P3V3_NODE1")
		)
		(pad "33" smd rect
			(at 4.549902 3.750056)
			(size 0.254 0.9144)
			(layers "F.Cu" "F.Mask" "F.Paste")
			(net "LAN2_LED_LINK_1000_N")
		)
		(pad "34" smd rect
			(at 4.549902 3.24993)
			(size 0.254 0.9144)
			(layers "F.Cu" "F.Mask" "F.Paste")
			(net "SMB_LAN2_CLK")
		)
		(pad "35" smd rect
			(at 4.549902 2.750058)
			(size 0.254 0.9144)
			(layers "F.Cu" "F.Mask" "F.Paste")
			(net "SMB_LAN2_ALT_N")
		)
		(pad "36" smd rect
			(at 4.549902 2.249932)
			(size 0.254 0.9144)
			(layers "F.Cu" "F.Mask" "F.Paste")
			(net "SMB_LAN2_DAT")
		)
		(pad "37" smd rect
			(at 4.549902 1.75006)
			(size 0.254 0.9144)
			(layers "F.Cu" "F.Mask" "F.Paste")
			(net "P1V05_LAN2")
		)
		(pad "38" smd rect
			(at 4.549902 1.249934)
			(size 0.254 0.9144)
			(layers "F.Cu" "F.Mask" "F.Paste")
			(net "PU_LAN2_TMS")
		)
		(pad "39" smd rect
			(at 4.549902 0.750062)
			(size 0.254 0.9144)
			(layers "F.Cu" "F.Mask" "F.Paste")
			(net "LAN2_AUX_PWR")
		)
		(pad "40" smd rect
			(at 4.549902 0.249936)
			(size 0.254 0.9144)
			(layers "F.Cu" "F.Mask" "F.Paste")
			(net "PU_LAN2_TDI")
		)
		(pad "41" smd rect
			(at 4.549902 -0.249936)
			(size 0.254 0.9144)
			(layers "F.Cu" "F.Mask" "F.Paste")
			(net "P1V05_LAN2")
		)
		(pad "42" smd rect
			(at 4.549902 -0.750062)
			(size 0.254 0.9144)
			(layers "F.Cu" "F.Mask" "F.Paste")
			(net "LAN2_XTAL_OUT")
		)
		(pad "43" smd rect
			(at 4.549902 -1.249934)
			(size 0.254 0.9144)
			(layers "F.Cu" "F.Mask" "F.Paste")
			(net "LAN2_XTAL_IN")
		)
		(pad "44" smd rect
			(at 4.549902 -1.75006)
			(size 0.254 0.9144)
			(layers "F.Cu" "F.Mask" "F.Paste")
			(net "P1V9_LAN2")
		)
		(pad "45" smd rect
			(at 4.549902 -2.249932)
			(size 0.254 0.9144)
			(layers "F.Cu" "F.Mask" "F.Paste")
			(net "N21357353")
		)
		(pad "46" smd rect
			(at 4.549902 -2.750058)
			(size 0.254 0.9144)
			(layers "F.Cu" "F.Mask" "F.Paste")
			(net "N21357373")
		)
		(pad "47" smd rect
			(at 4.549902 -3.24993)
			(size 0.254 0.9144)
			(layers "F.Cu" "F.Mask" "F.Paste")
			(net "P1V9_LAN2")
		)
		(pad "48" smd rect
			(at 4.549902 -3.750056)
			(size 0.254 0.9144)
			(layers "F.Cu" "F.Mask" "F.Paste")
			(net "LAN2_RST")
		)
		(pad "49" smd rect
			(at 3.750056 -4.549902 270)
			(size 0.254 0.9144)
			(layers "F.Cu" "F.Mask" "F.Paste")
			(net "LAN2_MDI3_DN")
		)
		(pad "50" smd rect
			(at 3.24993 -4.549902 270)
			(size 0.254 0.9144)
			(layers "F.Cu" "F.Mask" "F.Paste")
			(net "LAN2_MDI3_DP")
		)
		(pad "51" smd rect
			(at 2.750058 -4.549902 270)
			(size 0.254 0.9144)
			(layers "F.Cu" "F.Mask" "F.Paste")
			(net "P1V9_LAN2")
		)
		(pad "52" smd rect
			(at 2.249932 -4.549902 270)
			(size 0.254 0.9144)
			(layers "F.Cu" "F.Mask" "F.Paste")
			(net "LAN2_MDI2_DN")
		)
		(pad "53" smd rect
			(at 1.75006 -4.549902 270)
			(size 0.254 0.9144)
			(layers "F.Cu" "F.Mask" "F.Paste")
			(net "LAN2_MDI2_DP")
		)
		(pad "54" smd rect
			(at 1.249934 -4.549902 270)
			(size 0.254 0.9144)
			(layers "F.Cu" "F.Mask" "F.Paste")
			(net "LAN2_MDI1_DN")
		)
		(pad "55" smd rect
			(at 0.750062 -4.549902 270)
			(size 0.254 0.9144)
			(layers "F.Cu" "F.Mask" "F.Paste")
			(net "LAN2_MDI1_DP")
		)
		(pad "56" smd rect
			(at 0.249936 -4.549902 270)
			(size 0.254 0.9144)
			(layers "F.Cu" "F.Mask" "F.Paste")
			(net "P1V9_LAN2")
		)
		(pad "57" smd rect
			(at -0.249936 -4.549902 270)
			(size 0.254 0.9144)
			(layers "F.Cu" "F.Mask" "F.Paste")
			(net "LAN2_MDI0_DN")
		)
		(pad "58" smd rect
			(at -0.750062 -4.549902 270)
			(size 0.254 0.9144)
			(layers "F.Cu" "F.Mask" "F.Paste")
			(net "LAN2_MDI0_DP")
		)
		(pad "59" smd rect
			(at -1.249934 -4.549902 270)
			(size 0.254 0.9144)
			(layers "F.Cu" "F.Mask" "F.Paste")
			(net "LAN2_DIS_REG10")
		)
		(pad "60" smd rect
			(at -1.75006 -4.549902 270)
			(size 0.254 0.9144)
			(layers "F.Cu" "F.Mask" "F.Paste")
			(net "P1V05_LAN2")
		)
		(pad "61" smd rect
			(at -2.249932 -4.549902 270)
			(size 0.254 0.9144)
			(layers "F.Cu" "F.Mask" "F.Paste")
			(net "P1V9_LAN2")
		)
		(pad "62" smd rect
			(at -2.750058 -4.549902 270)
			(size 0.254 0.9144)
			(layers "F.Cu" "F.Mask" "F.Paste")
			(net "Net_1820")
		)
		(pad "63" smd rect
			(at -3.24993 -4.549902 270)
			(size 0.254 0.9144)
			(layers "F.Cu" "F.Mask" "F.Paste")
			(net "P1V9_LAN2")
		)
		(pad "64" smd rect
			(at -3.750056 -4.549902 270)
			(size 0.254 0.9144)
			(layers "F.Cu" "F.Mask" "F.Paste")
			(net "LAN2_CTRL_P1V9")
		)
		(pad "TH" smd rect
			(at 0 0 270)
			(size 5.4102 5.4102)
			(layers "F.Cu" "F.Mask" "F.Paste")
			(net "GND")
		)
		(zone
			(layer "F.Cu")
			(hatch none 0.5)
			(connect_pads
				(clearance 0)
			)
			(min_thickness 0.25)
			(keepout
				(tracks not_allowed)
				(vias allowed)
				(pads allowed)
				(copperpour not_allowed)
				(footprints allowed)
			)
			(placement
				(enabled no)
				(sheetname "")
			)
			(fill
				(thermal_gap 0.5)
				(thermal_bridge_width 0.5)
				(island_removal_mode 0)
			)
			(polygon
				(pts
					(xy 165.033198 -157.11043) (xy 165.033198 -149.08403) (xy 157.006798 -149.08403) (xy 157.006798 -157.11043)
					(xy 163.788598 -157.11043) (xy 163.788598 -155.89123) (xy 158.225998 -155.89123) (xy 158.225998 -150.30323)
					(xy 163.813998 -150.30323) (xy 163.813998 -157.11043) (xy 164.220398 -157.11043)
				)
			)
		)
		(zone
			(layers "F.Cu" "B.Cu" "In1.Cu" "In2.Cu" "In3.Cu" "In4.Cu" "In5.Cu" "In6.Cu"
				"In7.Cu" "In8.Cu"
			)
			(hatch none 0.5)
			(connect_pads
				(clearance 0)
			)
			(min_thickness 0.25)
			(keepout
				(tracks allowed)
				(vias not_allowed)
				(pads allowed)
				(copperpour not_allowed)
				(footprints allowed)
			)
			(placement
				(enabled no)
				(sheetname "")
			)
			(fill
				(thermal_gap 0.5)
				(thermal_bridge_width 0.5)
				(island_removal_mode 0)
			)
			(polygon
				(pts
					(xy 165.033198 -157.11043) (xy 165.033198 -149.08403) (xy 157.006798 -149.08403) (xy 157.006798 -157.11043)
					(xy 163.788598 -157.11043) (xy 163.788598 -155.89123) (xy 158.225998 -155.89123) (xy 158.225998 -150.30323)
					(xy 163.813998 -150.30323) (xy 163.813998 -157.11043)
				)
			)
		)
	)
)
